(kicad_pcb
	(version 20260206)
	(generator "pcbnew")
	(generator_version "10.0")
	(general
		(thickness 1.6)
		(legacy_teardrops no)
	)
	(paper "A4")
	(title_block
		(title "Wiwynn_Tioga_Pass_MB.brd")
		(comment 1 "Tioga Pass / footprints 2882-2888 of 4770")
	)
	(layers
		(0 "F.Cu" signal "TOP")
		(4 "In1.Cu" signal "L2GND")
		(6 "In2.Cu" signal "L3")
		(8 "In3.Cu" signal "L4GND")
		(10 "In4.Cu" signal "L5")
		(12 "In5.Cu" signal "L6GND")
		(14 "In6.Cu" signal "L7VCC")
		(16 "In7.Cu" signal "L8VCC")
		(18 "In8.Cu" signal "L9GND")
		(20 "In9.Cu" signal "L10")
		(22 "In10.Cu" signal "L11GND")
		(24 "In11.Cu" signal "L12")
		(26 "In12.Cu" signal "L13GND")
		(2 "B.Cu" signal "BOTTOM")
		(9 "F.Adhes" user "F.Adhesive")
		(11 "B.Adhes" user "B.Adhesive")
		(13 "F.Paste" user "Package Geometry/Pastemask Top")
		(15 "B.Paste" user "Package Geometry/Pastemask Bottom")
		(5 "F.SilkS" user "Ref Des/Silkscreen Top")
		(7 "B.SilkS" user "Ref Des/Silkscreen Bottom")
		(1 "F.Mask" user "Board Geometry/Soldermask Top")
		(3 "B.Mask" user "Board Geometry/Soldermask Bottom")
		(17 "Dwgs.User" user "User.Drawings")
		(19 "Cmts.User" user "User.Comments")
		(21 "Eco1.User" user "User.Eco1")
		(23 "Eco2.User" user "User.Eco2")
		(25 "Edge.Cuts" user "Board Geometry/Outline")
		(27 "Margin" user)
		(31 "F.CrtYd" user "Package Geometry/Place Bound Top")
		(29 "B.CrtYd" user "Package Geometry/Place Bound Bottom")
		(35 "F.Fab" user "Ref Des/Assembly Top")
		(33 "B.Fab" user "Ref Des/Assembly Bottom")
	)
	(footprint ""
		(layer "B.Cu")
		(at 449.707 -141.097 90)
		(property "Reference" "R25W158"
			(at 0.8382 -0.67818 90)
			(unlocked yes)
			(layer "B.SilkS")
			(effects
				(font
					(size 0.4064 0.254)
					(thickness 0.1524)
				)
				(justify left mirror)
			)
		)
		(property "Value" ""
			(at 0 0 90)
			(layer "B.Fab")
			(effects
				(font
					(size 1.27 1.27)
				)
				(justify mirror)
			)
		)
		(duplicate_pad_numbers_are_jumpers no)
		(fp_poly
			(pts
				(xy 0.2794 -0.1016) (xy -0.2794 -0.1016) (xy -0.2794 0.9906) (xy 0.2794 0.9906)
			)
			(stroke
				(width 0)
				(type default)
			)
			(fill no)
			(layer "B.CrtYd")
		)
		(fp_line
			(start 0.2794 -0.1016)
			(end 0.2794 0.9906)
			(stroke
				(width 0.1)
				(type default)
			)
			(layer "B.Fab")
		)
		(fp_line
			(start -0.2794 -0.1016)
			(end 0.2794 -0.1016)
			(stroke
				(width 0.1)
				(type default)
			)
			(layer "B.Fab")
		)
		(fp_line
			(start 0.2794 0.9906)
			(end -0.2794 0.9906)
			(stroke
				(width 0.1)
				(type default)
			)
			(layer "B.Fab")
		)
		(fp_line
			(start -0.2794 0.9906)
			(end -0.2794 -0.1016)
			(stroke
				(width 0.1)
				(type default)
			)
			(layer "B.Fab")
		)
		(pad "1" smd rect
			(at 0 0 270)
			(size 0.508 0.508)
			(layers "B.Cu" "B.Mask" "B.Paste")
			(net "P3V3_STBY")
		)
		(pad "2" smd rect
			(at 0 0.889 270)
			(size 0.508 0.508)
			(layers "B.Cu" "B.Mask" "B.Paste")
			(net "PU_GTL2014_3_DIR")
		)
		(zone
			(layer "B.Cu")
			(hatch none 0.5)
			(connect_pads
				(clearance 0)
			)
			(min_thickness 0.25)
			(keepout
				(tracks allowed)
				(vias not_allowed)
				(pads allowed)
				(copperpour not_allowed)
				(footprints allowed)
			)
			(placement
				(enabled no)
				(sheetname "")
			)
			(fill
				(thermal_gap 0.5)
				(thermal_bridge_width 0.5)
				(island_removal_mode 0)
			)
			(polygon
				(pts
					(xy 449.961 -141.351) (xy 449.961 -140.843) (xy 450.342 -140.843) (xy 450.342 -141.351)
				)
			)
		)
		(zone
			(layer "B.Cu")
			(hatch none 0.5)
			(connect_pads
				(clearance 0)
			)
			(min_thickness 0.25)
			(keepout
				(tracks not_allowed)
				(vias allowed)
				(pads allowed)
				(copperpour not_allowed)
				(footprints allowed)
			)
			(placement
				(enabled no)
				(sheetname "")
			)
			(fill
				(thermal_gap 0.5)
				(thermal_bridge_width 0.5)
				(island_removal_mode 0)
			)
			(polygon
				(pts
					(xy 450.342 -141.351) (xy 450.342 -140.843) (xy 449.961 -140.843) (xy 449.961 -141.351)
				)
			)
		)
	)
	(footprint ""
		(layer "B.Cu")
		(at 27.658568 -144.4752 180)
		(property "Reference" "R9L8"
			(at 0 0 0)
			(layer "B.SilkS")
			(hide yes)
			(effects
				(font
					(size 1.27 1.27)
				)
				(justify mirror)
			)
		)
		(property "Value" ""
			(at 0 0 0)
			(layer "B.Fab")
			(effects
				(font
					(size 1.27 1.27)
				)
				(justify mirror)
			)
		)
		(duplicate_pad_numbers_are_jumpers no)
		(fp_poly
			(pts
				(xy 0.2794 -0.1016) (xy -0.2794 -0.1016) (xy -0.2794 0.9906) (xy 0.2794 0.9906)
			)
			(stroke
				(width 0)
				(type default)
			)
			(fill no)
			(layer "B.CrtYd")
		)
		(fp_line
			(start 0.2794 0.9906)
			(end -0.2794 0.9906)
			(stroke
				(width 0.1)
				(type default)
			)
			(layer "B.Fab")
		)
		(fp_line
			(start 0.2794 -0.1016)
			(end 0.2794 0.9906)
			(stroke
				(width 0.1)
				(type default)
			)
			(layer "B.Fab")
		)
		(fp_line
			(start -0.2794 0.9906)
			(end -0.2794 -0.1016)
			(stroke
				(width 0.1)
				(type default)
			)
			(layer "B.Fab")
		)
		(fp_line
			(start -0.2794 -0.1016)
			(end 0.2794 -0.1016)
			(stroke
				(width 0.1)
				(type default)
			)
			(layer "B.Fab")
		)
		(pad "1" smd rect
			(at 0 0)
			(size 0.508 0.508)
			(layers "B.Cu" "B.Mask" "B.Paste")
			(net "M_L_CPU_VREF")
		)
		(pad "2" smd rect
			(at 0 0.889)
			(size 0.508 0.508)
			(layers "B.Cu" "B.Mask" "B.Paste")
			(net "M_L_VREF")
		)
		(zone
			(layer "B.Cu")
			(hatch none 0.5)
			(connect_pads
				(clearance 0)
			)
			(min_thickness 0.25)
			(keepout
				(tracks not_allowed)
				(vias allowed)
				(pads allowed)
				(copperpour not_allowed)
				(footprints allowed)
			)
			(placement
				(enabled no)
				(sheetname "")
			)
			(fill
				(thermal_gap 0.5)
				(thermal_bridge_width 0.5)
				(island_removal_mode 0)
			)
			(polygon
				(pts
					(xy 27.404568 -145.1102) (xy 27.912568 -145.1102) (xy 27.912568 -144.7292) (xy 27.404568 -144.7292)
				)
			)
		)
		(zone
			(layer "B.Cu")
			(hatch none 0.5)
			(connect_pads
				(clearance 0)
			)
			(min_thickness 0.25)
			(keepout
				(tracks allowed)
				(vias not_allowed)
				(pads allowed)
				(copperpour not_allowed)
				(footprints allowed)
			)
			(placement
				(enabled no)
				(sheetname "")
			)
			(fill
				(thermal_gap 0.5)
				(thermal_bridge_width 0.5)
				(island_removal_mode 0)
			)
			(polygon
				(pts
					(xy 27.404568 -144.7292) (xy 27.912568 -144.7292) (xy 27.912568 -145.1102) (xy 27.404568 -145.1102)
				)
			)
		)
	)
	(footprint ""
		(layer "B.Cu")
		(at 259.4864 -13.0556 90)
		(property "Reference" "C5G22"
			(at -1.64973 0.78994 180)
			(unlocked yes)
			(layer "B.SilkS")
			(effects
				(font
					(size 0.7874 0.5842)
					(thickness 0.1524)
				)
				(justify mirror)
			)
		)
		(property "Value" ""
			(at 0 0 90)
			(layer "B.Fab")
			(effects
				(font
					(size 1.27 1.27)
				)
				(justify mirror)
			)
		)
		(duplicate_pad_numbers_are_jumpers no)
		(fp_rect
			(start -0.7239 -0.2159)
			(end 0.7239 1.9939)
			(stroke
				(width 0)
				(type default)
			)
			(fill no)
			(layer "B.CrtYd")
		)
		(fp_line
			(start 0.7239 -0.2159)
			(end 0.7239 1.9939)
			(stroke
				(width 0.1)
				(type default)
			)
			(layer "B.Fab")
		)
		(fp_line
			(start -0.7239 -0.2159)
			(end 0.7239 -0.2159)
			(stroke
				(width 0.1)
				(type default)
			)
			(layer "B.Fab")
		)
		(fp_line
			(start 0.7239 1.9939)
			(end -0.7239 1.9939)
			(stroke
				(width 0.1)
				(type default)
			)
			(layer "B.Fab")
		)
		(fp_line
			(start -0.7239 1.9939)
			(end -0.7239 -0.2159)
			(stroke
				(width 0.1)
				(type default)
			)
			(layer "B.Fab")
		)
		(pad "1" smd rect
			(at 0 0 270)
			(size 1.27 1.016)
			(layers "B.Cu" "B.Mask" "B.Paste")
			(net "PVDDQ_ABC")
		)
		(pad "2" smd rect
			(at 0 1.778 270)
			(size 1.27 1.016)
			(layers "B.Cu" "B.Mask" "B.Paste")
			(net "GND")
		)
		(zone
			(layer "B.Cu")
			(hatch none 0.5)
			(connect_pads
				(clearance 0)
			)
			(min_thickness 0.25)
			(keepout
				(tracks not_allowed)
				(vias allowed)
				(pads allowed)
				(copperpour not_allowed)
				(footprints allowed)
			)
			(placement
				(enabled no)
				(sheetname "")
			)
			(fill
				(thermal_gap 0.5)
				(thermal_bridge_width 0.5)
				(island_removal_mode 0)
			)
			(polygon
				(pts
					(xy 259.9944 -12.4206) (xy 260.7564 -12.4206) (xy 260.7564 -13.6906) (xy 259.9944 -13.6906)
				)
			)
		)
	)
	(footprint ""
		(layer "B.Cu")
		(at 474.14942 -134.00024 90)
		(property "Reference" "U1W3"
			(at -2.2733 -1.09728 90)
			(unlocked yes)
			(layer "B.SilkS")
			(effects
				(font
					(size 0.4064 0.254)
					(thickness 0.1524)
				)
				(justify mirror)
			)
		)
		(property "Value" ""
			(at 0 0 90)
			(layer "B.Fab")
			(effects
				(font
					(size 1.27 1.27)
				)
				(justify mirror)
			)
		)
		(duplicate_pad_numbers_are_jumpers no)
		(fp_line
			(start -3.225292 -0.57404)
			(end -1.352804 -0.57404)
			(stroke
				(width 0.1524)
				(type default)
			)
			(layer "B.SilkS")
		)
		(fp_line
			(start -3.225038 2.52476)
			(end -1.348486 2.52476)
			(stroke
				(width 0.1524)
				(type default)
			)
			(layer "B.SilkS")
		)
		(fp_circle
			(center 1.971802 -0.212852)
			(end 1.971802 -0.085852)
			(stroke
				(width 0.254)
				(type default)
			)
			(fill no)
			(layer "B.SilkS")
		)
		(fp_poly
			(pts
				(xy -0.7366 -0.57404) (xy -3.8354 -0.57404) (xy -3.8354 2.52476) (xy -0.7366 2.52476)
			)
			(stroke
				(width 0)
				(type default)
			)
			(fill no)
			(layer "B.CrtYd")
		)
		(fp_line
			(start -0.7366 -0.57404)
			(end -3.8354 -0.57404)
			(stroke
				(width 0.1)
				(type default)
			)
			(layer "B.Fab")
		)
		(fp_line
			(start -3.8354 -0.57404)
			(end -3.8354 2.52476)
			(stroke
				(width 0.1)
				(type default)
			)
			(layer "B.Fab")
		)
		(fp_line
			(start -0.7366 2.52476)
			(end -0.7366 -0.57404)
			(stroke
				(width 0.1)
				(type default)
			)
			(layer "B.Fab")
		)
		(fp_line
			(start -3.8354 2.52476)
			(end -0.7366 2.52476)
			(stroke
				(width 0.1)
				(type default)
			)
			(layer "B.Fab")
		)
		(fp_circle
			(center 1.454404 -0.556514)
			(end 1.454404 -0.429514)
			(stroke
				(width 0.254)
				(type default)
			)
			(fill no)
			(layer "B.Fab")
		)
		(pad "1" smd rect
			(at 0 0 270)
			(size 1.778 0.4572)
			(layers "B.Cu" "B.Mask" "B.Paste")
			(net "P3V3_STBY")
		)
		(pad "2" smd rect
			(at 0 0.65024 270)
			(size 1.778 0.4572)
			(layers "B.Cu" "B.Mask" "B.Paste")
			(net "SMB_DEBUG_STBY_LVC3_SCL_CONN")
		)
		(pad "3" smd rect
			(at 0 1.30048 270)
			(size 1.778 0.4572)
			(layers "B.Cu" "B.Mask" "B.Paste")
			(net "SMB_DEBUG_STBY_LVC3_SDA_CONN")
		)
		(pad "4" smd rect
			(at 0 1.95072 270)
			(size 1.778 0.4572)
			(layers "B.Cu" "B.Mask" "B.Paste")
			(net "GND")
		)
		(pad "5" smd rect
			(at -4.572 1.95072 270)
			(size 1.778 0.4572)
			(layers "B.Cu" "B.Mask" "B.Paste")
			(net "DEBUG_CARD2_PRSNT")
		)
		(pad "6" smd rect
			(at -4.572 1.30048 270)
			(size 1.778 0.4572)
			(layers "B.Cu" "B.Mask" "B.Paste")
			(net "SMB_DEBUG_STBY_LVC3_SDA_R1")
		)
		(pad "7" smd rect
			(at -4.572 0.65024 270)
			(size 1.778 0.4572)
			(layers "B.Cu" "B.Mask" "B.Paste")
			(net "SMB_DEBUG_STBY_LVC3_SCL_R1")
		)
		(pad "8" smd rect
			(at -4.572 0 270)
			(size 1.778 0.4572)
			(layers "B.Cu" "B.Mask" "B.Paste")
			(net "P3V3_STBY")
		)
	)
	(footprint ""
		(layer "B.Cu")
		(at 408.6225 -109.22 -90)
		(property "Reference" "R6W24"
			(at 0.8382 -0.67818 270)
			(unlocked yes)
			(layer "B.SilkS")
			(effects
				(font
					(size 0.4064 0.254)
					(thickness 0.1524)
				)
				(justify left mirror)
			)
		)
		(property "Value" ""
			(at 0 0 90)
			(layer "B.Fab")
			(effects
				(font
					(size 1.27 1.27)
				)
				(justify mirror)
			)
		)
		(duplicate_pad_numbers_are_jumpers no)
		(fp_poly
			(pts
				(xy 0.2794 -0.1016) (xy -0.2794 -0.1016) (xy -0.2794 0.9906) (xy 0.2794 0.9906)
			)
			(stroke
				(width 0)
				(type default)
			)
			(fill no)
			(layer "B.CrtYd")
		)
		(fp_line
			(start -0.2794 0.9906)
			(end -0.2794 -0.1016)
			(stroke
				(width 0.1)
				(type default)
			)
			(layer "B.Fab")
		)
		(fp_line
			(start 0.2794 0.9906)
			(end -0.2794 0.9906)
			(stroke
				(width 0.1)
				(type default)
			)
			(layer "B.Fab")
		)
		(fp_line
			(start -0.2794 -0.1016)
			(end 0.2794 -0.1016)
			(stroke
				(width 0.1)
				(type default)
			)
			(layer "B.Fab")
		)
		(fp_line
			(start 0.2794 -0.1016)
			(end 0.2794 0.9906)
			(stroke
				(width 0.1)
				(type default)
			)
			(layer "B.Fab")
		)
		(pad "1" smd rect
			(at 0 0 90)
			(size 0.508 0.508)
			(layers "B.Cu" "B.Mask" "B.Paste")
			(net "P3V3_STBY")
		)
		(pad "2" smd rect
			(at 0 0.889 90)
			(size 0.508 0.508)
			(layers "B.Cu" "B.Mask" "B.Paste")
			(net "SMB_PMBUS_BMC_STBY_LVC3_SDA_R1")
		)
		(zone
			(layer "B.Cu")
			(hatch none 0.5)
			(connect_pads
				(clearance 0)
			)
			(min_thickness 0.25)
			(keepout
				(tracks not_allowed)
				(vias allowed)
				(pads allowed)
				(copperpour not_allowed)
				(footprints allowed)
			)
			(placement
				(enabled no)
				(sheetname "")
			)
			(fill
				(thermal_gap 0.5)
				(thermal_bridge_width 0.5)
				(island_removal_mode 0)
			)
			(polygon
				(pts
					(xy 407.9875 -108.966) (xy 407.9875 -109.474) (xy 408.3685 -109.474) (xy 408.3685 -108.966)
				)
			)
		)
		(zone
			(layer "B.Cu")
			(hatch none 0.5)
			(connect_pads
				(clearance 0)
			)
			(min_thickness 0.25)
			(keepout
				(tracks allowed)
				(vias not_allowed)
				(pads allowed)
				(copperpour not_allowed)
				(footprints allowed)
			)
			(placement
				(enabled no)
				(sheetname "")
			)
			(fill
				(thermal_gap 0.5)
				(thermal_bridge_width 0.5)
				(island_removal_mode 0)
			)
			(polygon
				(pts
					(xy 408.3685 -108.966) (xy 408.3685 -109.474) (xy 407.9875 -109.474) (xy 407.9875 -108.966)
				)
			)
		)
	)
	(footprint ""
		(layer "B.Cu")
		(at 372.869968 -51.34229 180)
		(property "Reference" "R3P38"
			(at 0 0 0)
			(layer "B.SilkS")
			(hide yes)
			(effects
				(font
					(size 1.27 1.27)
				)
				(justify mirror)
			)
		)
		(property "Value" ""
			(at 0 0 0)
			(layer "B.Fab")
			(effects
				(font
					(size 1.27 1.27)
				)
				(justify mirror)
			)
		)
		(duplicate_pad_numbers_are_jumpers no)
		(fp_poly
			(pts
				(xy 0.2794 -0.1016) (xy -0.2794 -0.1016) (xy -0.2794 0.9906) (xy 0.2794 0.9906)
			)
			(stroke
				(width 0)
				(type default)
			)
			(fill no)
			(layer "B.CrtYd")
		)
		(fp_line
			(start 0.2794 0.9906)
			(end -0.2794 0.9906)
			(stroke
				(width 0.1)
				(type default)
			)
			(layer "B.Fab")
		)
		(fp_line
			(start 0.2794 -0.1016)
			(end 0.2794 0.9906)
			(stroke
				(width 0.1)
				(type default)
			)
			(layer "B.Fab")
		)
		(fp_line
			(start -0.2794 0.9906)
			(end -0.2794 -0.1016)
			(stroke
				(width 0.1)
				(type default)
			)
			(layer "B.Fab")
		)
		(fp_line
			(start -0.2794 -0.1016)
			(end 0.2794 -0.1016)
			(stroke
				(width 0.1)
				(type default)
			)
			(layer "B.Fab")
		)
		(pad "1" smd rect
			(at 0 0)
			(size 0.508 0.508)
			(layers "B.Cu" "B.Mask" "B.Paste")
			(net "PVDDQ_ABC")
		)
		(pad "2" smd rect
			(at 0 0.889)
			(size 0.508 0.508)
			(layers "B.Cu" "B.Mask" "B.Paste")
			(net "PWRGD_CPU0_DRAMPWROK_ABC_G")
		)
		(zone
			(layer "B.Cu")
			(hatch none 0.5)
			(connect_pads
				(clearance 0)
			)
			(min_thickness 0.25)
			(keepout
				(tracks not_allowed)
				(vias allowed)
				(pads allowed)
				(copperpour not_allowed)
				(footprints allowed)
			)
			(placement
				(enabled no)
				(sheetname "")
			)
			(fill
				(thermal_gap 0.5)
				(thermal_bridge_width 0.5)
				(island_removal_mode 0)
			)
			(polygon
				(pts
					(xy 372.615968 -51.97729) (xy 373.123968 -51.97729) (xy 373.123968 -51.59629) (xy 372.615968 -51.59629)
				)
			)
		)
		(zone
			(layer "B.Cu")
			(hatch none 0.5)
			(connect_pads
				(clearance 0)
			)
			(min_thickness 0.25)
			(keepout
				(tracks allowed)
				(vias not_allowed)
				(pads allowed)
				(copperpour not_allowed)
				(footprints allowed)
			)
			(placement
				(enabled no)
				(sheetname "")
			)
			(fill
				(thermal_gap 0.5)
				(thermal_bridge_width 0.5)
				(island_removal_mode 0)
			)
			(polygon
				(pts
					(xy 372.615968 -51.59629) (xy 373.123968 -51.59629) (xy 373.123968 -51.97729) (xy 372.615968 -51.97729)
				)
			)
		)
	)
	(footprint ""
		(layer "B.Cu")
		(at 260.377686 -73.51014)
		(property "Reference" "C5P36"
			(at 0 0 0)
			(layer "B.SilkS")
			(hide yes)
			(effects
				(font
					(size 1.27 1.27)
				)
				(justify mirror)
			)
		)
		(property "Value" ""
			(at 0 0 0)
			(layer "B.Fab")
			(effects
				(font
					(size 1.27 1.27)
				)
				(justify mirror)
			)
		)
		(duplicate_pad_numbers_are_jumpers no)
		(fp_poly
			(pts
				(xy 0.7239 -0.2159) (xy -0.7239 -0.2159) (xy -0.7239 1.9939) (xy 0.7239 1.9939)
			)
			(stroke
				(width 0)
				(type default)
			)
			(fill no)
			(layer "B.CrtYd")
		)
		(fp_line
			(start -0.7239 -0.2159)
			(end 0.7239 -0.2159)
			(stroke
				(width 0.1)
				(type default)
			)
			(layer "B.Fab")
		)
		(fp_line
			(start -0.7239 1.9939)
			(end -0.7239 -0.2159)
			(stroke
				(width 0.1)
				(type default)
			)
			(layer "B.Fab")
		)
		(fp_line
			(start 0.7239 -0.2159)
			(end 0.7239 1.9939)
			(stroke
				(width 0.1)
				(type default)
			)
			(layer "B.Fab")
		)
		(fp_line
			(start 0.7239 1.9939)
			(end -0.7239 1.9939)
			(stroke
				(width 0.1)
				(type default)
			)
			(layer "B.Fab")
		)
		(pad "1" smd rect
			(at 0 0 180)
			(size 1.27 1.016)
			(layers "B.Cu" "B.Mask" "B.Paste")
			(net "PVCCIN_CPU0")
		)
		(pad "2" smd rect
			(at 0 1.778 180)
			(size 1.27 1.016)
			(layers "B.Cu" "B.Mask" "B.Paste")
			(net "GND")
		)
		(zone
			(layer "B.Cu")
			(hatch none 0.5)
			(connect_pads
				(clearance 0)
			)
			(min_thickness 0.25)
			(keepout
				(tracks not_allowed)
				(vias allowed)
				(pads allowed)
				(copperpour not_allowed)
				(footprints allowed)
			)
			(placement
				(enabled no)
				(sheetname "")
			)
			(fill
				(thermal_gap 0.5)
				(thermal_bridge_width 0.5)
				(island_removal_mode 0)
			)
			(polygon
				(pts
					(xy 261.012686 -73.00214) (xy 259.742686 -73.00214) (xy 259.742686 -72.24014) (xy 261.012686 -72.24014)
				)
			)
		)
	)
)
